# T6G (Grand Teton) — schematic netlist excerpt (pin names and nets, part order shuffled) for the footprints in the layout excerpt that follows; sources: Cadence DE-HDL packaged netlist, KiCad conversion of 04192023_DAF0TMB3IC0_F0TG_MB_C_brd_V02_OCP.brd

C1974  Q_CAP  0.1UF 25V 10% X7R  pkg 0402  page 126 : A = GPU_FPGA_THERM_OVERT_ISO_N ; B = GND
R337  Q_RES  0 5% CHIP  pkg 0402LF  page 161 : A = SMB_APML_CPU1_MUX2_SCL ; B = SMB_APML_CPU1_SCL

(kicad_pcb
	(version 20260206)
	(generator "pcbnew")
	(generator_version "10.0")
	(general
		(thickness 1.6)
		(legacy_teardrops no)
	)
	(paper "A4")
	(title_block
		(title "04192023_DAF0TMB3IC0_F0TG_MB_C_brd_V02_OCP.brd")
		(comment 1 "Grand Teton / footprints 6444-6445 of 8354")
	)
	(layers
		(0 "F.Cu" signal "TOP")
		(4 "In1.Cu" signal "GND")
		(6 "In2.Cu" signal "IN1")
		(8 "In3.Cu" signal "GND1")
		(10 "In4.Cu" signal "IN2")
		(12 "In5.Cu" signal "GND2")
		(14 "In6.Cu" signal "IN3")
		(16 "In7.Cu" signal "GND3")
		(18 "In8.Cu" signal "VCC")
		(20 "In9.Cu" signal "VCC1")
		(22 "In10.Cu" signal "GND4")
		(24 "In11.Cu" signal "IN4")
		(26 "In12.Cu" signal "GND5")
		(28 "In13.Cu" signal "IN5")
		(30 "In14.Cu" signal "GND6")
		(32 "In15.Cu" signal "IN6")
		(34 "In16.Cu" signal "GND7")
		(2 "B.Cu" signal "BOTTOM")
		(9 "F.Adhes" user "F.Adhesive")
		(11 "B.Adhes" user "B.Adhesive")
		(13 "F.Paste" user "Package Geometry/Pastemask Top")
		(15 "B.Paste" user "Package Geometry/Pastemask Bottom")
		(5 "F.SilkS" user "Ref Des/Silkscreen Top")
		(7 "B.SilkS" user "Ref Des/Silkscreen Bottom")
		(1 "F.Mask" user "Board Geometry/Soldermask Top")
		(3 "B.Mask" user "Board Geometry/Soldermask Bottom")
		(17 "Dwgs.User" user "User.Drawings")
		(19 "Cmts.User" user "User.Comments")
		(21 "Eco1.User" user "User.Eco1")
		(23 "Eco2.User" user "User.Eco2")
		(25 "Edge.Cuts" user "Board Geometry/Outline")
		(27 "Margin" user)
		(31 "F.CrtYd" user "Package Geometry/Place Bound Top")
		(29 "B.CrtYd" user "Package Geometry/Place Bound Bottom")
		(35 "F.Fab" user "Ref Des/Assembly Top")
		(33 "B.Fab" user "Ref Des/Assembly Bottom")
	)
	(footprint ""
		(layer "B.Cu")
		(at 51.766978 -431.904902 90)
		(property "Reference" "C1974"
			(at 0 0 90)
			(layer "B.SilkS")
			(hide yes)
			(effects
				(font
					(size 1.27 1.27)
				)
				(justify mirror)
			)
		)
		(property "Value" ""
			(at 0 0 90)
			(layer "B.Fab")
			(effects
				(font
					(size 1.27 1.27)
				)
				(justify mirror)
			)
		)
		(duplicate_pad_numbers_are_jumpers no)
		(fp_line
			(start 0.7874 -0.4064)
			(end -0.7874 -0.4064)
			(stroke
				(width 0.1524)
				(type default)
			)
			(layer "B.SilkS")
		)
		(fp_line
			(start -0.7874 -0.4064)
			(end -0.7874 0.4064)
			(stroke
				(width 0.1524)
				(type default)
			)
			(layer "B.SilkS")
		)
		(fp_line
			(start 0.7874 0.4064)
			(end 0.7874 -0.4064)
			(stroke
				(width 0.1524)
				(type default)
			)
			(layer "B.SilkS")
		)
		(fp_line
			(start -0.7874 0.4064)
			(end 0.7874 0.4064)
			(stroke
				(width 0.1524)
				(type default)
			)
			(layer "B.SilkS")
		)
		(fp_line
			(start 0.67945 -0.305054)
			(end 0.12065 -0.305054)
			(stroke
				(width 0.1)
				(type default)
			)
			(layer "B.Fab")
		)
		(fp_line
			(start 0.12065 -0.305054)
			(end 0.12065 -0.2794)
			(stroke
				(width 0.1)
				(type default)
			)
			(layer "B.Fab")
		)
		(fp_line
			(start -0.12065 -0.3048)
			(end -0.67945 -0.3048)
			(stroke
				(width 0.1)
				(type default)
			)
			(layer "B.Fab")
		)
		(fp_line
			(start -0.67945 -0.3048)
			(end -0.67945 0.3048)
			(stroke
				(width 0.1)
				(type default)
			)
			(layer "B.Fab")
		)
		(fp_line
			(start 0.12065 -0.2794)
			(end -0.12065 -0.2794)
			(stroke
				(width 0.1)
				(type default)
			)
			(layer "B.Fab")
		)
		(fp_line
			(start -0.12065 -0.2794)
			(end -0.12065 -0.3048)
			(stroke
				(width 0.1)
				(type default)
			)
			(layer "B.Fab")
		)
		(fp_line
			(start 0.12065 0.2794)
			(end 0.12065 0.3048)
			(stroke
				(width 0.1)
				(type default)
			)
			(layer "B.Fab")
		)
		(fp_line
			(start -0.120396 0.2794)
			(end 0.12065 0.2794)
			(stroke
				(width 0.1)
				(type default)
			)
			(layer "B.Fab")
		)
		(fp_line
			(start 0.67945 0.3048)
			(end 0.67945 -0.305054)
			(stroke
				(width 0.1)
				(type default)
			)
			(layer "B.Fab")
		)
		(fp_line
			(start 0.12065 0.3048)
			(end 0.67945 0.3048)
			(stroke
				(width 0.1)
				(type default)
			)
			(layer "B.Fab")
		)
		(fp_line
			(start -0.120396 0.3048)
			(end -0.120396 0.2794)
			(stroke
				(width 0.1)
				(type default)
			)
			(layer "B.Fab")
		)
		(fp_line
			(start -0.67945 0.3048)
			(end -0.120396 0.3048)
			(stroke
				(width 0.1)
				(type default)
			)
			(layer "B.Fab")
		)
		(pad "1" smd circle
			(at 0.40005 0 270)
			(size 0 0)
			(layers "B.Cu" "B.Mask" "B.Paste")
			(net "GPU_FPGA_THERM_OVERT_ISO_N")
		)
		(pad "2" smd circle
			(at -0.40005 0 270)
			(size 0 0)
			(layers "B.Cu" "B.Mask" "B.Paste")
			(net "GND")
		)
	)
	(footprint ""
		(layer "B.Cu")
		(at 235.839 -241.2111 90)
		(property "Reference" "R337"
			(at 0 0 90)
			(layer "B.SilkS")
			(hide yes)
			(effects
				(font
					(size 1.27 1.27)
				)
				(justify mirror)
			)
		)
		(property "Value" ""
			(at 0 0 90)
			(layer "B.Fab")
			(effects
				(font
					(size 1.27 1.27)
				)
				(justify mirror)
			)
		)
		(duplicate_pad_numbers_are_jumpers no)
		(fp_line
			(start 0.7874 -0.4064)
			(end -0.7874 -0.4064)
			(stroke
				(width 0.1524)
				(type default)
			)
			(layer "B.SilkS")
		)
		(fp_line
			(start -0.7874 -0.4064)
			(end -0.7874 0.4064)
			(stroke
				(width 0.1524)
				(type default)
			)
			(layer "B.SilkS")
		)
		(fp_line
			(start 0.7874 0.4064)
			(end 0.7874 -0.4064)
			(stroke
				(width 0.1524)
				(type default)
			)
			(layer "B.SilkS")
		)
		(fp_line
			(start -0.7874 0.4064)
			(end 0.7874 0.4064)
			(stroke
				(width 0.1524)
				(type default)
			)
			(layer "B.SilkS")
		)
		(fp_line
			(start 0.67945 -0.305054)
			(end 0.12065 -0.305054)
			(stroke
				(width 0.1)
				(type default)
			)
			(layer "B.Fab")
		)
		(fp_line
			(start 0.12065 -0.305054)
			(end 0.12065 -0.2794)
			(stroke
				(width 0.1)
				(type default)
			)
			(layer "B.Fab")
		)
		(fp_line
			(start -0.12065 -0.3048)
			(end -0.67945 -0.3048)
			(stroke
				(width 0.1)
				(type default)
			)
			(layer "B.Fab")
		)
		(fp_line
			(start -0.67945 -0.3048)
			(end -0.67945 0.3048)
			(stroke
				(width 0.1)
				(type default)
			)
			(layer "B.Fab")
		)
		(fp_line
			(start 0.12065 -0.2794)
			(end -0.12065 -0.2794)
			(stroke
				(width 0.1)
				(type default)
			)
			(layer "B.Fab")
		)
		(fp_line
			(start -0.12065 -0.2794)
			(end -0.12065 -0.3048)
			(stroke
				(width 0.1)
				(type default)
			)
			(layer "B.Fab")
		)
		(fp_line
			(start 0.12065 0.2794)
			(end 0.12065 0.3048)
			(stroke
				(width 0.1)
				(type default)
			)
			(layer "B.Fab")
		)
		(fp_line
			(start -0.120396 0.2794)
			(end 0.12065 0.2794)
			(stroke
				(width 0.1)
				(type default)
			)
			(layer "B.Fab")
		)
		(fp_line
			(start 0.67945 0.3048)
			(end 0.67945 -0.305054)
			(stroke
				(width 0.1)
				(type default)
			)
			(layer "B.Fab")
		)
		(fp_line
			(start 0.12065 0.3048)
			(end 0.67945 0.3048)
			(stroke
				(width 0.1)
				(type default)
			)
			(layer "B.Fab")
		)
		(fp_line
			(start -0.120396 0.3048)
			(end -0.120396 0.2794)
			(stroke
				(width 0.1)
				(type default)
			)
			(layer "B.Fab")
		)
		(fp_line
			(start -0.67945 0.3048)
			(end -0.120396 0.3048)
			(stroke
				(width 0.1)
				(type default)
			)
			(layer "B.Fab")
		)
		(pad "1" smd rect
			(at 0.40005 0 90)
			(size 0.4572 0.508)
			(layers "B.Cu" "B.Mask" "B.Paste")
			(net "SMB_APML_CPU1_MUX2_SCL")
		)
		(pad "2" smd rect
			(at -0.40005 0 90)
			(size 0.4572 0.508)
			(layers "B.Cu" "B.Mask" "B.Paste")
			(net "SMB_APML_CPU1_SCL")
		)
	)
)
